#ISCELL
  mstr_misc dns *
  *
#ISCELL
  pure_quanta quanta_title_block_c *
  *
#ISCELL
  pure_quanta_power p1v0 *
  page431_i1
#ISCELL
  pure_quanta_power vcc_core *
  page431_i10
#ISCELL
  pure_quanta_power universal_gnd *
  page431_i11
#ISCELL
  pure_quanta_power universal_gnd *
  page431_i12
#CELL
  pure_quanta q_res *
  page431_i13
#CELL
  pure_quanta q_res *
  page431_i14
#ISCELL
  pure_quanta_power universal_gnd *
  page431_i15
#ISCELL
  pure_quanta_power universal_gnd *
  page431_i16
#CELL
  pure_quanta pt5161lrs *
  page431_i17
#CELL
  pure_quanta q_res *
  page431_i18
#CELL
  pure_quanta q_res *
  page431_i19
#ISCELL
  pure_quanta_power p1v0 *
  page431_i3
#ISCELL
  pure_quanta_power universal_gnd *
  page431_i4
#CELL
  pure_quanta pt5161lrs *
  page431_i6
#ISCELL
  pure_quanta_power p1v0 *
  page431_i7
#ISCELL
  pure_quanta_power p1v0 *
  page431_i8
#ISCELL
  pure_quanta_power vcc_core *
  page431_i9
